(kicad_pcb
	(version 20260206)
	(generator "pcbnew")
	(generator_version "10.0")
	(general
		(thickness 1.6)
		(legacy_teardrops no)
	)
	(paper "A4")
	(title_block
		(title "pdpb — Lightning_PDPB_BRD.brd")
		(comment 1 "Lightning (Wiwynn / Facebook NVMe JBOF) / footprint 378 of 1140 (J19), pads 115-202 of 202")
	)
	(layers
		(0 "F.Cu" signal "TOP")
		(4 "In1.Cu" signal "L2GND")
		(6 "In2.Cu" signal "L3")
		(8 "In3.Cu" signal "L4VCC")
		(10 "In4.Cu" signal "L5VCC")
		(12 "In5.Cu" signal "L6")
		(14 "In6.Cu" signal "L7GND")
		(2 "B.Cu" signal "BOTTOM")
		(9 "F.Adhes" user "F.Adhesive")
		(11 "B.Adhes" user "B.Adhesive")
		(13 "F.Paste" user "Package Geometry/Pastemask Top")
		(15 "B.Paste" user "Package Geometry/Pastemask Bottom")
		(5 "F.SilkS" user "Ref Des/Silkscreen Top")
		(7 "B.SilkS" user "Ref Des/Silkscreen Bottom")
		(1 "F.Mask" user "Board Geometry/Soldermask Top")
		(3 "B.Mask" user "Board Geometry/Soldermask Bottom")
		(17 "Dwgs.User" user "User.Drawings")
		(19 "Cmts.User" user "User.Comments")
		(21 "Eco1.User" user "User.Eco1")
		(23 "Eco2.User" user "User.Eco2")
		(25 "Edge.Cuts" user "Board Geometry/Outline")
		(27 "Margin" user)
		(31 "F.CrtYd" user "Package Geometry/Place Bound Top")
		(29 "B.CrtYd" user "Package Geometry/Place Bound Bottom")
		(35 "F.Fab" user "Ref Des/Assembly Top")
		(33 "B.Fab" user "Ref Des/Assembly Bottom")
	)
	(footprint ""
		(layer "F.Cu")
		(at 2.999994 -193.142108 90)
		(property "Reference" "J19"
			(at 0 0 90)
			(layer "F.SilkS")
			(hide yes)
			(effects
				(font
					(size 1.27 1.27)
				)
			)
		)
		(property "Value" "PCISLT200-5-GP-U"
			(at -48.7045 -6.7818 90)
			(unlocked yes)
			(layer "F.Fab")
			(hide yes)
			(effects
				(font
					(size 1.016 1.016)
					(thickness 0.1524)
				)
			)
		)
		(property "Device Type" "G639F200221431HR-U"
			(at -48.7045 -8.3058 90)
			(unlocked yes)
			(layer "F.Fab")
			(hide yes)
			(effects
				(font
					(size 1.016 1.016)
					(thickness 0.1524)
				)
			)
		)
		(duplicate_pad_numbers_are_jumpers no)
		(pad "B13" smd rect
			(at -31.599886 -1.131062 90)
			(size 0.508 2.4892)
			(drill
				(offset 0 0.381)
			)
			(layers "F.Cu" "F.Mask" "F.Paste")
			(net "PE_RX3_DR14_P")
		)
		(pad "B14" smd rect
			(at -30.80004 -1.131062 90)
			(size 0.508 2.4892)
			(drill
				(offset 0 0.381)
			)
			(layers "F.Cu" "F.Mask" "F.Paste")
			(net "GND")
		)
		(pad "B15" smd rect
			(at -29.99994 -1.131062 90)
			(size 0.508 2.4892)
			(drill
				(offset 0 0.381)
			)
			(layers "F.Cu" "F.Mask" "F.Paste")
			(net "GND")
		)
		(pad "B16" smd rect
			(at -29.200094 -1.131062 90)
			(size 0.508 2.4892)
			(drill
				(offset 0 0.381)
			)
			(layers "F.Cu" "F.Mask" "F.Paste")
			(net "PE_RX4_DR14_N")
		)
		(pad "B17" smd rect
			(at -28.399994 -1.131062 90)
			(size 0.508 2.4892)
			(drill
				(offset 0 0.381)
			)
			(layers "F.Cu" "F.Mask" "F.Paste")
			(net "PE_RX4_DR14_P")
		)
		(pad "B18" smd rect
			(at -27.599894 -1.131062 90)
			(size 0.508 2.4892)
			(drill
				(offset 0 0.381)
			)
			(layers "F.Cu" "F.Mask" "F.Paste")
			(net "GND")
		)
		(pad "B19" smd rect
			(at -26.800048 -1.131062 90)
			(size 0.508 2.4892)
			(drill
				(offset 0 0.381)
			)
			(layers "F.Cu" "F.Mask" "F.Paste")
			(net "GND")
		)
		(pad "B20" smd rect
			(at -25.999948 -1.131062 90)
			(size 0.508 2.4892)
			(drill
				(offset 0 0.381)
			)
			(layers "F.Cu" "F.Mask" "F.Paste")
			(net "PE_RX1_DR13_N")
		)
		(pad "B21" smd rect
			(at -25.200102 -1.131062 90)
			(size 0.508 2.4892)
			(drill
				(offset 0 0.381)
			)
			(layers "F.Cu" "F.Mask" "F.Paste")
			(net "PE_RX1_DR13_P")
		)
		(pad "B22" smd rect
			(at -24.400002 -1.131062 90)
			(size 0.508 2.4892)
			(drill
				(offset 0 0.381)
			)
			(layers "F.Cu" "F.Mask" "F.Paste")
			(net "GND")
		)
		(pad "B23" smd rect
			(at -23.599902 -1.131062 90)
			(size 0.508 2.4892)
			(drill
				(offset 0 0.381)
			)
			(layers "F.Cu" "F.Mask" "F.Paste")
			(net "GND")
		)
		(pad "B24" smd rect
			(at -22.800056 -1.131062 90)
			(size 0.508 2.4892)
			(drill
				(offset 0 0.381)
			)
			(layers "F.Cu" "F.Mask" "F.Paste")
			(net "PE_RX2_DR13_N")
		)
		(pad "B25" smd rect
			(at -21.999956 -1.131062 90)
			(size 0.508 2.4892)
			(drill
				(offset 0 0.381)
			)
			(layers "F.Cu" "F.Mask" "F.Paste")
			(net "PE_RX2_DR13_P")
		)
		(pad "B26" smd rect
			(at -21.20011 -1.131062 90)
			(size 0.508 2.4892)
			(drill
				(offset 0 0.381)
			)
			(layers "F.Cu" "F.Mask" "F.Paste")
			(net "GND")
		)
		(pad "B27" smd rect
			(at -20.40001 -1.131062 90)
			(size 0.508 2.4892)
			(drill
				(offset 0 0.381)
			)
			(layers "F.Cu" "F.Mask" "F.Paste")
			(net "GND")
		)
		(pad "B28" smd rect
			(at -19.59991 -1.131062 90)
			(size 0.508 2.4892)
			(drill
				(offset 0 0.381)
			)
			(layers "F.Cu" "F.Mask" "F.Paste")
			(net "PE_RX3_DR13_N")
		)
		(pad "B29" smd rect
			(at -18.800064 -1.131062 90)
			(size 0.508 2.4892)
			(drill
				(offset 0 0.381)
			)
			(layers "F.Cu" "F.Mask" "F.Paste")
			(net "PE_RX3_DR13_P")
		)
		(pad "B30" smd rect
			(at -17.999964 -1.131062 90)
			(size 0.508 2.4892)
			(drill
				(offset 0 0.381)
			)
			(layers "F.Cu" "F.Mask" "F.Paste")
			(net "GND")
		)
		(pad "B31" smd rect
			(at -17.200118 -1.131062 90)
			(size 0.508 2.4892)
			(drill
				(offset 0 0.381)
			)
			(layers "F.Cu" "F.Mask" "F.Paste")
			(net "GND")
		)
		(pad "B32" smd rect
			(at -16.400018 -1.131062 90)
			(size 0.508 2.4892)
			(drill
				(offset 0 0.381)
			)
			(layers "F.Cu" "F.Mask" "F.Paste")
			(net "PE_RX4_DR13_N")
		)
		(pad "B33" smd rect
			(at -15.599918 -1.131062 90)
			(size 0.508 2.4892)
			(drill
				(offset 0 0.381)
			)
			(layers "F.Cu" "F.Mask" "F.Paste")
			(net "PE_RX4_DR13_P")
		)
		(pad "B34" smd rect
			(at -14.800072 -1.131062 90)
			(size 0.508 2.4892)
			(drill
				(offset 0 0.381)
			)
			(layers "F.Cu" "F.Mask" "F.Paste")
			(net "GND")
		)
		(pad "B35" smd rect
			(at -13.999972 -1.131062 90)
			(size 0.508 2.4892)
			(drill
				(offset 0 0.381)
			)
			(layers "F.Cu" "F.Mask" "F.Paste")
			(net "GND")
		)
		(pad "B36" smd rect
			(at -13.200126 -1.131062 90)
			(size 0.508 2.4892)
			(drill
				(offset 0 0.381)
			)
			(layers "F.Cu" "F.Mask" "F.Paste")
			(net "PE_RX1_DR9_N")
		)
		(pad "B37" smd rect
			(at -12.400026 -1.131062 90)
			(size 0.508 2.4892)
			(drill
				(offset 0 0.381)
			)
			(layers "F.Cu" "F.Mask" "F.Paste")
			(net "PE_RX1_DR9_P")
		)
		(pad "B38" smd rect
			(at -11.599926 -1.131062 90)
			(size 0.508 2.4892)
			(drill
				(offset 0 0.381)
			)
			(layers "F.Cu" "F.Mask" "F.Paste")
			(net "GND")
		)
		(pad "B39" smd rect
			(at -10.80008 -1.131062 90)
			(size 0.508 2.4892)
			(drill
				(offset 0 0.381)
			)
			(layers "F.Cu" "F.Mask" "F.Paste")
			(net "GND")
		)
		(pad "B40" smd rect
			(at -9.99998 -1.131062 90)
			(size 0.508 2.4892)
			(drill
				(offset 0 0.381)
			)
			(layers "F.Cu" "F.Mask" "F.Paste")
			(net "PE_RX2_DR9_N")
		)
		(pad "B41" smd rect
			(at -9.19988 -1.131062 90)
			(size 0.508 2.4892)
			(drill
				(offset 0 0.381)
			)
			(layers "F.Cu" "F.Mask" "F.Paste")
			(net "PE_RX2_DR9_P")
		)
		(pad "B42" smd rect
			(at -8.400034 -1.131062 90)
			(size 0.508 2.4892)
			(drill
				(offset 0 0.381)
			)
			(layers "F.Cu" "F.Mask" "F.Paste")
			(net "GND")
		)
		(pad "B43" smd rect
			(at -7.599934 -1.131062 90)
			(size 0.508 2.4892)
			(drill
				(offset 0 0.381)
			)
			(layers "F.Cu" "F.Mask" "F.Paste")
			(net "SSD14_PERST_N")
		)
		(pad "B44" smd rect
			(at -6.800088 -1.131062 90)
			(size 0.508 2.4892)
			(drill
				(offset 0 0.381)
			)
			(layers "F.Cu" "F.Mask" "F.Paste")
			(net "SSD4_PERST_N")
		)
		(pad "B45" smd rect
			(at -2.800096 -1.131062 90)
			(size 0.508 2.4892)
			(drill
				(offset 0 0.381)
			)
			(layers "F.Cu" "F.Mask" "F.Paste")
			(net "GND")
		)
		(pad "B46" smd rect
			(at -1.999996 -1.131062 90)
			(size 0.508 2.4892)
			(drill
				(offset 0 0.381)
			)
			(layers "F.Cu" "F.Mask" "F.Paste")
			(net "PE_RX3_DR9_N")
		)
		(pad "B47" smd rect
			(at -1.199896 -1.131062 90)
			(size 0.508 2.4892)
			(drill
				(offset 0 0.381)
			)
			(layers "F.Cu" "F.Mask" "F.Paste")
			(net "PE_RX3_DR9_P")
		)
		(pad "B48" smd rect
			(at -0.40005 -1.131062 90)
			(size 0.508 2.4892)
			(drill
				(offset 0 0.381)
			)
			(layers "F.Cu" "F.Mask" "F.Paste")
			(net "GND")
		)
		(pad "B49" smd rect
			(at 0.40005 -1.131062 90)
			(size 0.508 2.4892)
			(drill
				(offset 0 0.381)
			)
			(layers "F.Cu" "F.Mask" "F.Paste")
			(net "GND")
		)
		(pad "B50" smd rect
			(at 1.199896 -1.131062 90)
			(size 0.508 2.4892)
			(drill
				(offset 0 0.381)
			)
			(layers "F.Cu" "F.Mask" "F.Paste")
			(net "PE_RX4_DR9_N")
		)
		(pad "B51" smd rect
			(at 1.999996 -1.131062 90)
			(size 0.508 2.4892)
			(drill
				(offset 0 0.381)
			)
			(layers "F.Cu" "F.Mask" "F.Paste")
			(net "PE_RX4_DR9_P")
		)
		(pad "B52" smd rect
			(at 2.800096 -1.131062 90)
			(size 0.508 2.4892)
			(drill
				(offset 0 0.381)
			)
			(layers "F.Cu" "F.Mask" "F.Paste")
			(net "GND")
		)
		(pad "B53" smd rect
			(at 3.599942 -1.131062 90)
			(size 0.508 2.4892)
			(drill
				(offset 0 0.381)
			)
			(layers "F.Cu" "F.Mask" "F.Paste")
			(net "SSD4_CLK0_OE_R_N")
		)
		(pad "B54" smd rect
			(at 4.400042 -1.131062 90)
			(size 0.508 2.4892)
			(drill
				(offset 0 0.381)
			)
			(layers "F.Cu" "F.Mask" "F.Paste")
			(net "ATTN_LED_DR4_N")
		)
		(pad "B55" smd rect
			(at 5.199888 -1.131062 90)
			(size 0.508 2.4892)
			(drill
				(offset 0 0.381)
			)
			(layers "F.Cu" "F.Mask" "F.Paste")
			(net "SSD4_PWREN")
		)
		(pad "B56" smd rect
			(at 5.999988 -1.131062 90)
			(size 0.508 2.4892)
			(drill
				(offset 0 0.381)
			)
			(layers "F.Cu" "F.Mask" "F.Paste")
			(net "GND")
		)
		(pad "B57" smd rect
			(at 6.800088 -1.131062 90)
			(size 0.508 2.4892)
			(drill
				(offset 0 0.381)
			)
			(layers "F.Cu" "F.Mask" "F.Paste")
			(net "PE_RX1_DR8_N")
		)
		(pad "B58" smd rect
			(at 7.599934 -1.131062 90)
			(size 0.508 2.4892)
			(drill
				(offset 0 0.381)
			)
			(layers "F.Cu" "F.Mask" "F.Paste")
			(net "PE_RX1_DR8_P")
		)
		(pad "B59" smd rect
			(at 8.400034 -1.131062 90)
			(size 0.508 2.4892)
			(drill
				(offset 0 0.381)
			)
			(layers "F.Cu" "F.Mask" "F.Paste")
			(net "GND")
		)
		(pad "B60" smd rect
			(at 9.19988 -1.131062 90)
			(size 0.508 2.4892)
			(drill
				(offset 0 0.381)
			)
			(layers "F.Cu" "F.Mask" "F.Paste")
			(net "GND")
		)
		(pad "B61" smd rect
			(at 9.99998 -1.131062 90)
			(size 0.508 2.4892)
			(drill
				(offset 0 0.381)
			)
			(layers "F.Cu" "F.Mask" "F.Paste")
			(net "PE_RX2_DR8_N")
		)
		(pad "B62" smd rect
			(at 10.80008 -1.131062 90)
			(size 0.508 2.4892)
			(drill
				(offset 0 0.381)
			)
			(layers "F.Cu" "F.Mask" "F.Paste")
			(net "PE_RX2_DR8_P")
		)
		(pad "B63" smd rect
			(at 11.599926 -1.131062 90)
			(size 0.508 2.4892)
			(drill
				(offset 0 0.381)
			)
			(layers "F.Cu" "F.Mask" "F.Paste")
			(net "GND")
		)
		(pad "B64" smd rect
			(at 12.400026 -1.131062 90)
			(size 0.508 2.4892)
			(drill
				(offset 0 0.381)
			)
			(layers "F.Cu" "F.Mask" "F.Paste")
			(net "GND")
		)
		(pad "B65" smd rect
			(at 13.200126 -1.131062 90)
			(size 0.508 2.4892)
			(drill
				(offset 0 0.381)
			)
			(layers "F.Cu" "F.Mask" "F.Paste")
			(net "PE_RX3_DR8_N")
		)
		(pad "B66" smd rect
			(at 13.999972 -1.131062 90)
			(size 0.508 2.4892)
			(drill
				(offset 0 0.381)
			)
			(layers "F.Cu" "F.Mask" "F.Paste")
			(net "PE_RX3_DR8_P")
		)
		(pad "B67" smd rect
			(at 14.800072 -1.131062 90)
			(size 0.508 2.4892)
			(drill
				(offset 0 0.381)
			)
			(layers "F.Cu" "F.Mask" "F.Paste")
			(net "GND")
		)
		(pad "B68" smd rect
			(at 15.599918 -1.131062 90)
			(size 0.508 2.4892)
			(drill
				(offset 0 0.381)
			)
			(layers "F.Cu" "F.Mask" "F.Paste")
			(net "GND")
		)
		(pad "B69" smd rect
			(at 16.400018 -1.131062 90)
			(size 0.508 2.4892)
			(drill
				(offset 0 0.381)
			)
			(layers "F.Cu" "F.Mask" "F.Paste")
			(net "PE_RX4_DR8_N")
		)
		(pad "B70" smd rect
			(at 17.200118 -1.131062 90)
			(size 0.508 2.4892)
			(drill
				(offset 0 0.381)
			)
			(layers "F.Cu" "F.Mask" "F.Paste")
			(net "PE_RX4_DR8_P")
		)
		(pad "B71" smd rect
			(at 17.999964 -1.131062 90)
			(size 0.508 2.4892)
			(drill
				(offset 0 0.381)
			)
			(layers "F.Cu" "F.Mask" "F.Paste")
			(net "GND")
		)
		(pad "B72" smd rect
			(at 18.800064 -1.131062 90)
			(size 0.508 2.4892)
			(drill
				(offset 0 0.381)
			)
			(layers "F.Cu" "F.Mask" "F.Paste")
			(net "GND")
		)
		(pad "B73" smd rect
			(at 19.59991 -1.131062 90)
			(size 0.508 2.4892)
			(drill
				(offset 0 0.381)
			)
			(layers "F.Cu" "F.Mask" "F.Paste")
			(net "PE_RX1_DR12_N")
		)
		(pad "B74" smd rect
			(at 20.40001 -1.131062 90)
			(size 0.508 2.4892)
			(drill
				(offset 0 0.381)
			)
			(layers "F.Cu" "F.Mask" "F.Paste")
			(net "PE_RX1_DR12_P")
		)
		(pad "B75" smd rect
			(at 21.20011 -1.131062 90)
			(size 0.508 2.4892)
			(drill
				(offset 0 0.381)
			)
			(layers "F.Cu" "F.Mask" "F.Paste")
			(net "GND")
		)
		(pad "B76" smd rect
			(at 21.999956 -1.131062 90)
			(size 0.508 2.4892)
			(drill
				(offset 0 0.381)
			)
			(layers "F.Cu" "F.Mask" "F.Paste")
			(net "GND")
		)
		(pad "B77" smd rect
			(at 22.800056 -1.131062 90)
			(size 0.508 2.4892)
			(drill
				(offset 0 0.381)
			)
			(layers "F.Cu" "F.Mask" "F.Paste")
			(net "PE_RX2_DR12_N")
		)
		(pad "B78" smd rect
			(at 23.599902 -1.131062 90)
			(size 0.508 2.4892)
			(drill
				(offset 0 0.381)
			)
			(layers "F.Cu" "F.Mask" "F.Paste")
			(net "PE_RX2_DR12_P")
		)
		(pad "B79" smd rect
			(at 24.400002 -1.131062 90)
			(size 0.508 2.4892)
			(drill
				(offset 0 0.381)
			)
			(layers "F.Cu" "F.Mask" "F.Paste")
			(net "GND")
		)
		(pad "B80" smd rect
			(at 25.200102 -1.131062 90)
			(size 0.508 2.4892)
			(drill
				(offset 0 0.381)
			)
			(layers "F.Cu" "F.Mask" "F.Paste")
			(net "GND")
		)
		(pad "B81" smd rect
			(at 25.999948 -1.131062 90)
			(size 0.508 2.4892)
			(drill
				(offset 0 0.381)
			)
			(layers "F.Cu" "F.Mask" "F.Paste")
			(net "PE_RX3_DR12_N")
		)
		(pad "B82" smd rect
			(at 26.800048 -1.131062 90)
			(size 0.508 2.4892)
			(drill
				(offset 0 0.381)
			)
			(layers "F.Cu" "F.Mask" "F.Paste")
			(net "PE_RX3_DR12_P")
		)
		(pad "B83" smd rect
			(at 27.599894 -1.131062 90)
			(size 0.508 2.4892)
			(drill
				(offset 0 0.381)
			)
			(layers "F.Cu" "F.Mask" "F.Paste")
			(net "GND")
		)
		(pad "B84" smd rect
			(at 28.399994 -1.131062 90)
			(size 0.508 2.4892)
			(drill
				(offset 0 0.381)
			)
			(layers "F.Cu" "F.Mask" "F.Paste")
			(net "GND")
		)
		(pad "B85" smd rect
			(at 29.200094 -1.131062 90)
			(size 0.508 2.4892)
			(drill
				(offset 0 0.381)
			)
			(layers "F.Cu" "F.Mask" "F.Paste")
			(net "PE_RX4_DR12_N")
		)
		(pad "B86" smd rect
			(at 29.99994 -1.131062 90)
			(size 0.508 2.4892)
			(drill
				(offset 0 0.381)
			)
			(layers "F.Cu" "F.Mask" "F.Paste")
			(net "PE_RX4_DR12_P")
		)
		(pad "B87" smd rect
			(at 30.80004 -1.131062 90)
			(size 0.508 2.4892)
			(drill
				(offset 0 0.381)
			)
			(layers "F.Cu" "F.Mask" "F.Paste")
			(net "GND")
		)
		(pad "B88" smd rect
			(at 31.599886 -1.131062 90)
			(size 0.508 2.4892)
			(drill
				(offset 0 0.381)
			)
			(layers "F.Cu" "F.Mask" "F.Paste")
			(net "SSD8_CLK0_OE_R_N")
		)
		(pad "B89" smd rect
			(at 32.399986 -1.131062 90)
			(size 0.508 2.4892)
			(drill
				(offset 0 0.381)
			)
			(layers "F.Cu" "F.Mask" "F.Paste")
			(net "ATTN_LED_DR8_N")
		)
		(pad "B90" smd rect
			(at 33.200086 -1.131062 90)
			(size 0.508 2.4892)
			(drill
				(offset 0 0.381)
			)
			(layers "F.Cu" "F.Mask" "F.Paste")
			(net "SSD8_PWREN")
		)
		(pad "B91" smd rect
			(at 33.999932 -1.131062 90)
			(size 0.508 2.4892)
			(drill
				(offset 0 0.381)
			)
			(layers "F.Cu" "F.Mask" "F.Paste")
			(net "SSD8_PERST_N")
		)
		(pad "B92" smd rect
			(at 34.800032 -1.131062 90)
			(size 0.508 2.4892)
			(drill
				(offset 0 0.381)
			)
			(layers "F.Cu" "F.Mask" "F.Paste")
			(net "GND")
		)
		(pad "B93" smd rect
			(at 35.599878 -1.131062 90)
			(size 0.508 2.4892)
			(drill
				(offset 0 0.381)
			)
			(layers "F.Cu" "F.Mask" "F.Paste")
			(net "PE_RX1_DR4_N")
		)
		(pad "B94" smd rect
			(at 36.399978 -1.131062 90)
			(size 0.508 2.4892)
			(drill
				(offset 0 0.381)
			)
			(layers "F.Cu" "F.Mask" "F.Paste")
			(net "PE_RX1_DR4_P")
		)
		(pad "B95" smd rect
			(at 37.200078 -1.131062 90)
			(size 0.508 2.4892)
			(drill
				(offset 0 0.381)
			)
			(layers "F.Cu" "F.Mask" "F.Paste")
			(net "GND")
		)
		(pad "B96" smd rect
			(at 37.999924 -1.131062 90)
			(size 0.508 2.4892)
			(drill
				(offset 0 0.381)
			)
			(layers "F.Cu" "F.Mask" "F.Paste")
			(net "GND")
		)
		(pad "B97" smd rect
			(at 38.800024 -1.131062 90)
			(size 0.508 2.4892)
			(drill
				(offset 0 0.381)
			)
			(layers "F.Cu" "F.Mask" "F.Paste")
			(net "PE_RX2_DR4_N")
		)
		(pad "B98" smd rect
			(at 39.600124 -1.131062 90)
			(size 0.508 2.4892)
			(drill
				(offset 0 0.381)
			)
			(layers "F.Cu" "F.Mask" "F.Paste")
			(net "PE_RX2_DR4_P")
		)
		(pad "B99" smd rect
			(at 40.39997 -1.131062 90)
			(size 0.508 2.4892)
			(drill
				(offset 0 0.381)
			)
			(layers "F.Cu" "F.Mask" "F.Paste")
			(net "GND")
		)
		(pad "B100" smd rect
			(at 41.20007 -1.131062 90)
			(size 0.508 2.4892)
			(drill
				(offset 0 0.381)
			)
			(layers "F.Cu" "F.Mask" "F.Paste")
			(net "I2C_MUX_RESET_PEB")
		)
	)
)
